# S9S_MB_2U (Grand Teton) — schematic netlist excerpt (pin names and nets, part order shuffled) for the footprints in the layout excerpt that follows; sources: Cadence DE-HDL packaged netlist, KiCad conversion of 03242023_DA0F0TMBIJ0_F0T_Motherboard_J_brd_V01_OCP.brd

C2351  Q_CAP  0.1UF 25V 10% EMPTY  pkg 0402  page 167 : A = P2E_MB_BMC_TX_BUF2_DP<0> ; B = P2E_MB_BMC_TX_BUF_C_DP<0>
R1601  Q_RES  10K 1% CHIP  pkg 0402LF  page 183 : A = IRQ_SML0_ALERT_N ; B = P3V3_AUX

(kicad_pcb
	(version 20260206)
	(generator "pcbnew")
	(generator_version "10.0")
	(general
		(thickness 1.6)
		(legacy_teardrops no)
	)
	(paper "A4")
	(title_block
		(title "03242023_DA0F0TMBIJ0_F0T_Motherboard_J_brd_V01_OCP.brd")
		(comment 1 "Grand Teton / footprints 1098-1099 of 6105")
	)
	(layers
		(0 "F.Cu" signal "TOP")
		(4 "In1.Cu" signal "GND")
		(6 "In2.Cu" signal "IN1")
		(8 "In3.Cu" signal "GND1")
		(10 "In4.Cu" signal "IN2")
		(12 "In5.Cu" signal "GND2")
		(14 "In6.Cu" signal "IN3")
		(16 "In7.Cu" signal "GND3")
		(18 "In8.Cu" signal "VCC")
		(20 "In9.Cu" signal "VCC1")
		(22 "In10.Cu" signal "GND4")
		(24 "In11.Cu" signal "IN4")
		(26 "In12.Cu" signal "GND5")
		(28 "In13.Cu" signal "IN5")
		(30 "In14.Cu" signal "GND6")
		(32 "In15.Cu" signal "IN6")
		(34 "In16.Cu" signal "GND7")
		(2 "B.Cu" signal "BOTTOM")
		(9 "F.Adhes" user "F.Adhesive")
		(11 "B.Adhes" user "B.Adhesive")
		(13 "F.Paste" user "Package Geometry/Pastemask Top")
		(15 "B.Paste" user "Package Geometry/Pastemask Bottom")
		(5 "F.SilkS" user "Ref Des/Silkscreen Top")
		(7 "B.SilkS" user "Ref Des/Silkscreen Bottom")
		(1 "F.Mask" user "Board Geometry/Soldermask Top")
		(3 "B.Mask" user "Board Geometry/Soldermask Bottom")
		(17 "Dwgs.User" user "User.Drawings")
		(19 "Cmts.User" user "User.Comments")
		(21 "Eco1.User" user "User.Eco1")
		(23 "Eco2.User" user "User.Eco2")
		(25 "Edge.Cuts" user "Board Geometry/Outline")
		(27 "Margin" user)
		(31 "F.CrtYd" user "Package Geometry/Place Bound Top")
		(29 "B.CrtYd" user "Package Geometry/Place Bound Bottom")
		(35 "F.Fab" user "Ref Des/Assembly Top")
		(33 "B.Fab" user "Ref Des/Assembly Bottom")
	)
	(footprint ""
		(layer "F.Cu")
		(at 18.640806 -396.810738 -90)
		(property "Reference" "C2351"
			(at 0 0 270)
			(layer "F.SilkS")
			(hide yes)
			(effects
				(font
					(size 1.27 1.27)
				)
			)
		)
		(property "Value" ""
			(at 0 0 270)
			(layer "F.Fab")
			(effects
				(font
					(size 1.27 1.27)
				)
			)
		)
		(duplicate_pad_numbers_are_jumpers no)
		(fp_line
			(start 0.7874 0.4064)
			(end -0.7874 0.4064)
			(stroke
				(width 0.1524)
				(type default)
			)
			(layer "F.SilkS")
		)
		(fp_line
			(start -0.7874 -0.4064)
			(end 0.001778 -0.4064)
			(stroke
				(width 0.1524)
				(type default)
			)
			(layer "F.SilkS")
		)
		(fp_line
			(start 0.7874 -0.4064)
			(end 0.7874 0.4064)
			(stroke
				(width 0.1524)
				(type default)
			)
			(layer "F.SilkS")
		)
		(fp_line
			(start -0.6858 0.3048)
			(end -0.6858 -0.3048)
			(stroke
				(width 0.1)
				(type default)
			)
			(layer "F.Fab")
		)
		(fp_line
			(start -0.1016 0.3048)
			(end -0.6858 0.3048)
			(stroke
				(width 0.1)
				(type default)
			)
			(layer "F.Fab")
		)
		(fp_line
			(start 0.1016 0.3048)
			(end 0.1016 0.2794)
			(stroke
				(width 0.1)
				(type default)
			)
			(layer "F.Fab")
		)
		(fp_line
			(start 0.6858 0.3048)
			(end 0.1016 0.3048)
			(stroke
				(width 0.1)
				(type default)
			)
			(layer "F.Fab")
		)
		(fp_line
			(start -0.1016 0.2794)
			(end -0.1016 0.3048)
			(stroke
				(width 0.1)
				(type default)
			)
			(layer "F.Fab")
		)
		(fp_line
			(start 0.1016 0.2794)
			(end -0.1016 0.2794)
			(stroke
				(width 0.1)
				(type default)
			)
			(layer "F.Fab")
		)
		(fp_line
			(start -0.1016 -0.2794)
			(end 0.1016 -0.2794)
			(stroke
				(width 0.1)
				(type default)
			)
			(layer "F.Fab")
		)
		(fp_line
			(start 0.1016 -0.2794)
			(end 0.1016 -0.3048)
			(stroke
				(width 0.1)
				(type default)
			)
			(layer "F.Fab")
		)
		(fp_line
			(start -0.6858 -0.3048)
			(end -0.1016 -0.3048)
			(stroke
				(width 0.1)
				(type default)
			)
			(layer "F.Fab")
		)
		(fp_line
			(start -0.1016 -0.3048)
			(end -0.1016 -0.2794)
			(stroke
				(width 0.1)
				(type default)
			)
			(layer "F.Fab")
		)
		(fp_line
			(start 0.1016 -0.3048)
			(end 0.6858 -0.3048)
			(stroke
				(width 0.1)
				(type default)
			)
			(layer "F.Fab")
		)
		(fp_line
			(start 0.6858 -0.3048)
			(end 0.6858 0.3048)
			(stroke
				(width 0.1)
				(type default)
			)
			(layer "F.Fab")
		)
		(pad "1" smd rect
			(at -0.40005 0 90)
			(size 0.4572 0.508)
			(layers "F.Cu" "F.Mask" "F.Paste")
			(net "P2E_MB_BMC_TX_BUF2_DP<0>")
		)
		(pad "2" smd rect
			(at 0.40005 0 90)
			(size 0.4572 0.508)
			(layers "F.Cu" "F.Mask" "F.Paste")
			(net "P2E_MB_BMC_TX_BUF_C_DP<0>")
		)
	)
	(footprint ""
		(layer "F.Cu")
		(at 312.443622 -34.102548 180)
		(property "Reference" "R1601"
			(at 0 0 180)
			(layer "F.SilkS")
			(hide yes)
			(effects
				(font
					(size 1.27 1.27)
				)
			)
		)
		(property "Value" ""
			(at 0 0 180)
			(layer "F.Fab")
			(effects
				(font
					(size 1.27 1.27)
				)
			)
		)
		(duplicate_pad_numbers_are_jumpers no)
		(fp_line
			(start 0.7874 0.4064)
			(end -0.7874 0.4064)
			(stroke
				(width 0.1524)
				(type default)
			)
			(layer "F.SilkS")
		)
		(fp_line
			(start 0.7874 -0.4064)
			(end 0.7874 0.4064)
			(stroke
				(width 0.1524)
				(type default)
			)
			(layer "F.SilkS")
		)
		(fp_line
			(start -0.7874 0.4064)
			(end -0.7874 -0.4064)
			(stroke
				(width 0.1524)
				(type default)
			)
			(layer "F.SilkS")
		)
		(fp_line
			(start -0.7874 -0.4064)
			(end 0.7874 -0.4064)
			(stroke
				(width 0.1524)
				(type default)
			)
			(layer "F.SilkS")
		)
		(fp_line
			(start 0.67945 0.3048)
			(end 0.120396 0.3048)
			(stroke
				(width 0.1)
				(type default)
			)
			(layer "F.Fab")
		)
		(fp_line
			(start 0.67945 -0.3048)
			(end 0.67945 0.3048)
			(stroke
				(width 0.1)
				(type default)
			)
			(layer "F.Fab")
		)
		(fp_line
			(start 0.12065 -0.2794)
			(end 0.12065 -0.3048)
			(stroke
				(width 0.1)
				(type default)
			)
			(layer "F.Fab")
		)
		(fp_line
			(start 0.12065 -0.3048)
			(end 0.67945 -0.3048)
			(stroke
				(width 0.1)
				(type default)
			)
			(layer "F.Fab")
		)
		(fp_line
			(start 0.120396 0.3048)
			(end 0.120396 0.2794)
			(stroke
				(width 0.1)
				(type default)
			)
			(layer "F.Fab")
		)
		(fp_line
			(start 0.120396 0.2794)
			(end -0.12065 0.2794)
			(stroke
				(width 0.1)
				(type default)
			)
			(layer "F.Fab")
		)
		(fp_line
			(start -0.12065 0.3048)
			(end -0.67945 0.3048)
			(stroke
				(width 0.1)
				(type default)
			)
			(layer "F.Fab")
		)
		(fp_line
			(start -0.12065 0.2794)
			(end -0.12065 0.3048)
			(stroke
				(width 0.1)
				(type default)
			)
			(layer "F.Fab")
		)
		(fp_line
			(start -0.12065 -0.2794)
			(end 0.12065 -0.2794)
			(stroke
				(width 0.1)
				(type default)
			)
			(layer "F.Fab")
		)
		(fp_line
			(start -0.12065 -0.305054)
			(end -0.12065 -0.2794)
			(stroke
				(width 0.1)
				(type default)
			)
			(layer "F.Fab")
		)
		(fp_line
			(start -0.67945 0.3048)
			(end -0.67945 -0.305054)
			(stroke
				(width 0.1)
				(type default)
			)
			(layer "F.Fab")
		)
		(fp_line
			(start -0.67945 -0.305054)
			(end -0.12065 -0.305054)
			(stroke
				(width 0.1)
				(type default)
			)
			(layer "F.Fab")
		)
		(pad "1" smd circle
			(at -0.40005 0 180)
			(size 0 0)
			(layers "F.Cu" "F.Mask" "F.Paste")
			(net "IRQ_SML0_ALERT_N")
		)
		(pad "2" smd circle
			(at 0.40005 0 180)
			(size 0 0)
			(layers "F.Cu" "F.Mask" "F.Paste")
			(net "P3V3_AUX")
		)
	)
)
